(kicad_pcb
	(version 20241229)
	(generator "pcbnew")
	(generator_version "9.0")
	(general
		(thickness 1.62)
		(legacy_teardrops no)
	)
	(paper "A4")
	(title_block
		(title "OCuLink to 10GbE adapter")
		(date "2026-02-23")
		(rev "1.1.0")
		(company "Antmicro Ltd")
		(comment 1 "www.antmicro.com")
		(comment 9 "footprints 136-141 of 510")
	)
	(layers
		(0 "F.Cu" signal)
		(4 "In1.Cu" signal)
		(6 "In2.Cu" signal)
		(8 "In3.Cu" signal)
		(10 "In4.Cu" signal)
		(12 "In5.Cu" signal)
		(14 "In6.Cu" signal)
		(2 "B.Cu" signal)
		(9 "F.Adhes" user "F.Adhesive")
		(11 "B.Adhes" user "B.Adhesive")
		(13 "F.Paste" user)
		(15 "B.Paste" user)
		(5 "F.SilkS" user "F.Silkscreen")
		(7 "B.SilkS" user "B.Silkscreen")
		(1 "F.Mask" user)
		(3 "B.Mask" user)
		(17 "Dwgs.User" user "User.Drawings")
		(19 "Cmts.User" user "User.Comments")
		(21 "Eco1.User" user "User.Eco1")
		(23 "Eco2.User" user "User.Eco2")
		(25 "Edge.Cuts" user)
		(27 "Margin" user)
		(31 "F.CrtYd" user "F.Courtyard")
		(29 "B.CrtYd" user "B.Courtyard")
		(35 "F.Fab" user)
		(33 "B.Fab" user)
	)
	(footprint "antmicro-footprints:C_0603_1608Metric_EIA"
		(layer "F.Cu")
		(at 77.2 80.950001 180)
		(descr "Capacitor SMD 0603, IPC-7351 Density Level A")
		(tags "Capacitor 0603")
		(property "Reference" "C155"
			(at -1.4 7.400001 0)
			(layer "F.SilkS")
			(effects
				(font
					(size 0.7 0.7)
					(thickness 0.15)
				)
				(justify right top)
			)
		)
		(property "Value" "C_22u_16V_0603"
			(at -1.42757 1.770288 0)
			(layer "F.Fab")
			(hide yes)
			(effects
				(font
					(size 0.7 0.7)
					(thickness 0.15)
				)
				(justify right top)
			)
		)
		(property "Datasheet" "https://product.samsungsem.com/mlcc/CL10A226MO7JZN.do"
			(at 0 0 0)
			(layer "F.Fab")
			(hide yes)
			(effects
				(font
					(size 1.27 1.27)
					(thickness 0.15)
				)
			)
		)
		(property "Description" "SMD Multilayer Ceramic Capacitor"
			(at 0 0 0)
			(layer "F.Fab")
			(hide yes)
			(effects
				(font
					(size 1.27 1.27)
					(thickness 0.15)
				)
			)
		)
		(property "MPN" "CL10A226MO7JZNC"
			(at 0 0 180)
			(unlocked yes)
			(layer "F.Fab")
			(hide yes)
			(effects
				(font
					(size 1 1)
					(thickness 0.15)
				)
			)
		)
		(property "Manufacturer" "Samsung Electro-Mechanics"
			(at 0 0 180)
			(unlocked yes)
			(layer "F.Fab")
			(hide yes)
			(effects
				(font
					(size 1 1)
					(thickness 0.15)
				)
			)
		)
		(property "License" "Apache-2.0"
			(at 0 0 180)
			(unlocked yes)
			(layer "F.Fab")
			(hide yes)
			(effects
				(font
					(size 1 1)
					(thickness 0.15)
				)
			)
		)
		(property "Author" "Antmicro"
			(at 0 0 180)
			(unlocked yes)
			(layer "F.Fab")
			(hide yes)
			(effects
				(font
					(size 1 1)
					(thickness 0.15)
				)
			)
		)
		(property "Val" "22u"
			(at 0 0 180)
			(unlocked yes)
			(layer "F.Fab")
			(hide yes)
			(effects
				(font
					(size 1 1)
					(thickness 0.15)
				)
			)
		)
		(property "Voltage" "16V"
			(at 0 0 180)
			(unlocked yes)
			(layer "F.Fab")
			(hide yes)
			(effects
				(font
					(size 1 1)
					(thickness 0.15)
				)
			)
		)
		(property "Dielectric" ""
			(at 0 0 180)
			(unlocked yes)
			(layer "F.Fab")
			(hide yes)
			(effects
				(font
					(size 1 1)
					(thickness 0.15)
				)
			)
		)
		(sheetname "/X710-AT2 power/")
		(sheetfile "x710-at2-power.kicad_sch")
		(attr smd)
		(fp_line
			(start -0.15 0.55)
			(end 0.15 0.55)
			(stroke
				(width 0.15)
				(type solid)
			)
			(layer "F.SilkS")
		)
		(fp_line
			(start -0.15 -0.55)
			(end 0.15 -0.55)
			(stroke
				(width 0.15)
				(type solid)
			)
			(layer "F.SilkS")
		)
		(fp_rect
			(start -1.25 -0.65)
			(end 1.25 0.65)
			(stroke
				(width 0.05)
				(type solid)
			)
			(fill no)
			(layer "F.CrtYd")
		)
		(fp_rect
			(start -0.8 -0.45)
			(end 0.8 0.45)
			(stroke
				(width 0.15)
				(type solid)
			)
			(fill no)
			(layer "F.Fab")
		)
		(pad "1" smd roundrect
			(at -0.7 0 180)
			(size 0.8 1.1)
			(layers "F.Cu" "F.Mask" "F.Paste")
			(roundrect_rratio 0.2)
			(net 28 "GND")
			(pintype "passive")
		)
		(pad "2" smd roundrect
			(at 0.7 0 180)
			(size 0.8 1.1)
			(layers "F.Cu" "F.Mask" "F.Paste")
			(roundrect_rratio 0.2)
			(net 7 "+3V3")
			(pintype "passive")
		)
	)
	(footprint "antmicro-footprints:C_0603_1608Metric"
		(layer "F.Cu")
		(at 97.9 97.95 180)
		(descr "Capacitor SMD 0603")
		(tags "capacitor 0603")
		(property "Reference" "C146"
			(at -3.75 0.35 0)
			(layer "F.SilkS")
			(effects
				(font
					(size 0.7 0.7)
					(thickness 0.15)
				)
				(justify left top)
			)
		)
		(property "Value" "C_10u_10V_X7R_0603"
			(at -1.42757 1.770288 0)
			(layer "F.Fab")
			(hide yes)
			(effects
				(font
					(size 0.7 0.7)
					(thickness 0.15)
				)
				(justify right top)
			)
		)
		(property "Datasheet" "https://www.murata.com/products/productdetail?partno=GRM188Z71A106KA73%23"
			(at 0 0 0)
			(layer "F.Fab")
			(hide yes)
			(effects
				(font
					(size 1.27 1.27)
					(thickness 0.15)
				)
			)
		)
		(property "Description" "SMD Multilayer Ceramic Capacitor,  10µF, 10V, 0603, ±10%, X7R"
			(at 0 0 0)
			(layer "F.Fab")
			(hide yes)
			(effects
				(font
					(size 1.27 1.27)
					(thickness 0.15)
				)
			)
		)
		(property "MPN" "GRM188Z71A106KA73D"
			(at 0 0 180)
			(unlocked yes)
			(layer "F.Fab")
			(hide yes)
			(effects
				(font
					(size 1 1)
					(thickness 0.15)
				)
			)
		)
		(property "Val" "10u"
			(at 0 0 180)
			(unlocked yes)
			(layer "F.Fab")
			(hide yes)
			(effects
				(font
					(size 1 1)
					(thickness 0.15)
				)
			)
		)
		(property "Voltage" "10V"
			(at 0 0 180)
			(unlocked yes)
			(layer "F.Fab")
			(hide yes)
			(effects
				(font
					(size 1 1)
					(thickness 0.15)
				)
			)
		)
		(property "Dielectric" "X7R"
			(at 0 0 180)
			(unlocked yes)
			(layer "F.Fab")
			(hide yes)
			(effects
				(font
					(size 1 1)
					(thickness 0.15)
				)
			)
		)
		(property "Manufacturer" "Murata"
			(at 0 0 180)
			(unlocked yes)
			(layer "F.Fab")
			(hide yes)
			(effects
				(font
					(size 1 1)
					(thickness 0.15)
				)
			)
		)
		(property "License" "Apache-2.0"
			(at 0 0 180)
			(unlocked yes)
			(layer "F.Fab")
			(hide yes)
			(effects
				(font
					(size 1 1)
					(thickness 0.15)
				)
			)
		)
		(property "Author" "Antmicro"
			(at 0 0 180)
			(unlocked yes)
			(layer "F.Fab")
			(hide yes)
			(effects
				(font
					(size 1 1)
					(thickness 0.15)
				)
			)
		)
		(sheetname "/X710-AT2 power/")
		(sheetfile "x710-at2-power.kicad_sch")
		(attr smd)
		(fp_line
			(start -0.15 0.4)
			(end 0.15 0.4)
			(stroke
				(width 0.15)
				(type solid)
			)
			(layer "F.SilkS")
		)
		(fp_line
			(start -0.15 -0.4)
			(end 0.15 -0.4)
			(stroke
				(width 0.15)
				(type solid)
			)
			(layer "F.SilkS")
		)
		(fp_rect
			(start -1.25 -0.65)
			(end 1.25 0.65)
			(stroke
				(width 0.05)
				(type solid)
			)
			(fill no)
			(layer "F.CrtYd")
		)
		(fp_rect
			(start -0.8 -0.4)
			(end 0.8 0.4)
			(stroke
				(width 0.15)
				(type solid)
			)
			(fill no)
			(layer "F.Fab")
		)
		(pad "1" smd roundrect
			(at -0.7 0 180)
			(size 0.8 1)
			(layers "F.Cu" "F.Mask" "F.Paste")
			(roundrect_rratio 0.2)
			(net 28 "GND")
			(pintype "passive")
		)
		(pad "2" smd roundrect
			(at 0.7 0 180)
			(size 0.8 1)
			(layers "F.Cu" "F.Mask" "F.Paste")
			(roundrect_rratio 0.2)
			(net 7 "+3V3")
			(pintype "passive")
		)
	)
	(footprint "antmicro-footprints:C_0402_1005Metric"
		(layer "F.Cu")
		(at 57.099999 108.25 -90)
		(descr "Capacitor SMD 0402")
		(tags "capacitor SMD 0402")
		(property "Reference" "C33"
			(at 5.68 -1.750001 270)
			(layer "F.SilkS")
			(effects
				(font
					(size 0.7 0.7)
					(thickness 0.15)
				)
				(justify right top)
			)
		)
		(property "Value" "C_1u_25V_0402"
			(at -1.022927 2.155213 90)
			(layer "F.Fab")
			(hide yes)
			(effects
				(font
					(size 0.7 0.7)
					(thickness 0.15)
				)
				(justify right top)
			)
		)
		(property "Datasheet" "https://www.murata.com/products/productdetail?partno=GRM155R61E105KE11%23"
			(at 0 0 90)
			(layer "F.Fab")
			(hide yes)
			(effects
				(font
					(size 1.27 1.27)
					(thickness 0.15)
				)
			)
		)
		(property "Description" "SMD Multilayer Ceramic Capacitor, 1 µF, 25 V, 0402 [1005 Metric], ± 10%, X5R, GRM Series"
			(at 0 0 90)
			(layer "F.Fab")
			(hide yes)
			(effects
				(font
					(size 1.27 1.27)
					(thickness 0.15)
				)
			)
		)
		(property "MPN" "GRM155R61E105KE11J"
			(at 0 0 270)
			(unlocked yes)
			(layer "F.Fab")
			(hide yes)
			(effects
				(font
					(size 1 1)
					(thickness 0.15)
				)
			)
		)
		(property "Manufacturer" "Murata"
			(at 0 0 270)
			(unlocked yes)
			(layer "F.Fab")
			(hide yes)
			(effects
				(font
					(size 1 1)
					(thickness 0.15)
				)
			)
		)
		(property "License" "Apache-2.0"
			(at 0 0 270)
			(unlocked yes)
			(layer "F.Fab")
			(hide yes)
			(effects
				(font
					(size 1 1)
					(thickness 0.15)
				)
			)
		)
		(property "Author" "Antmicro"
			(at 0 0 270)
			(unlocked yes)
			(layer "F.Fab")
			(hide yes)
			(effects
				(font
					(size 1 1)
					(thickness 0.15)
				)
			)
		)
		(property "Val" "1u"
			(at 0 0 270)
			(unlocked yes)
			(layer "F.Fab")
			(hide yes)
			(effects
				(font
					(size 1 1)
					(thickness 0.15)
				)
			)
		)
		(property "Voltage" "25V"
			(at 0 0 270)
			(unlocked yes)
			(layer "F.Fab")
			(hide yes)
			(effects
				(font
					(size 1 1)
					(thickness 0.15)
				)
			)
		)
		(property "Dielectric" "X5R"
			(at 0 0 270)
			(unlocked yes)
			(layer "F.Fab")
			(hide yes)
			(effects
				(font
					(size 1 1)
					(thickness 0.15)
				)
			)
		)
		(sheetname "/Power/")
		(sheetfile "power.kicad_sch")
		(attr smd)
		(fp_rect
			(start -0.925 -0.47)
			(end 0.925 0.47)
			(stroke
				(width 0.05)
				(type default)
			)
			(fill no)
			(layer "F.CrtYd")
		)
		(fp_line
			(start -0.494 0.248)
			(end -0.494 -0.25)
			(stroke
				(width 0.15)
				(type solid)
			)
			(layer "F.Fab")
		)
		(fp_line
			(start 0.504 0.248)
			(end -0.494 0.248)
			(stroke
				(width 0.15)
				(type solid)
			)
			(layer "F.Fab")
		)
		(fp_line
			(start -0.494 -0.25)
			(end 0.504 -0.25)
			(stroke
				(width 0.15)
				(type solid)
			)
			(layer "F.Fab")
		)
		(fp_line
			(start 0.504 -0.25)
			(end 0.504 0.248)
			(stroke
				(width 0.15)
				(type solid)
			)
			(layer "F.Fab")
		)
		(pad "1" smd roundrect
			(at -0.48 0 270)
			(size 0.59 0.64)
			(layers "F.Cu" "F.Mask" "F.Paste")
			(roundrect_rratio 0.25)
			(net 28 "GND")
			(pintype "passive")
		)
		(pad "2" smd roundrect
			(at 0.48 0 270)
			(size 0.59 0.64)
			(layers "F.Cu" "F.Mask" "F.Paste")
			(roundrect_rratio 0.25)
			(net 328 "/Power/1V0_VCC")
			(pintype "passive")
		)
	)
	(footprint "antmicro-footprints:C_0402_1005Metric"
		(layer "F.Cu")
		(at 103 65.285 -90)
		(descr "Capacitor SMD 0402")
		(tags "capacitor SMD 0402")
		(property "Reference" "C192"
			(at 0.792273 -0.499995 270)
			(layer "F.SilkS")
			(effects
				(font
					(size 0.7 0.7)
					(thickness 0.15)
				)
				(justify right bottom)
			)
		)
		(property "Value" "C_220n_16V_0402"
			(at -1.022927 2.155213 270)
			(layer "F.Fab")
			(hide yes)
			(effects
				(font
					(size 0.7 0.7)
					(thickness 0.15)
				)
				(justify left bottom)
			)
		)
		(property "Datasheet" "https://www.murata.com/products/productdetail?partno=GRM155R71C224KA12%23"
			(at 0 0 270)
			(layer "F.Fab")
			(hide yes)
			(effects
				(font
					(size 1.27 1.27)
					(thickness 0.15)
				)
			)
		)
		(property "Description" "SMD Multilayer Ceramic Capacitor, 0.22 µF, 16 V, 0402 [1005 Metric], ± 10%, X7R, GRM Series"
			(at 0 0 270)
			(layer "F.Fab")
			(hide yes)
			(effects
				(font
					(size 1.27 1.27)
					(thickness 0.15)
				)
			)
		)
		(property "MPN" "GRM155R71C224KA12D"
			(at 0 0 270)
			(unlocked yes)
			(layer "F.Fab")
			(hide yes)
			(effects
				(font
					(size 1 1)
					(thickness 0.15)
				)
			)
		)
		(property "Manufacturer" "Murata"
			(at 0 0 270)
			(unlocked yes)
			(layer "F.Fab")
			(hide yes)
			(effects
				(font
					(size 1 1)
					(thickness 0.15)
				)
			)
		)
		(property "License" "Apache-2.0"
			(at 0 0 270)
			(unlocked yes)
			(layer "F.Fab")
			(hide yes)
			(effects
				(font
					(size 1 1)
					(thickness 0.15)
				)
			)
		)
		(property "Author" "Antmicro"
			(at 0 0 270)
			(unlocked yes)
			(layer "F.Fab")
			(hide yes)
			(effects
				(font
					(size 1 1)
					(thickness 0.15)
				)
			)
		)
		(property "Val" "220n"
			(at 0 0 270)
			(unlocked yes)
			(layer "F.Fab")
			(hide yes)
			(effects
				(font
					(size 1 1)
					(thickness 0.15)
				)
			)
		)
		(property "Voltage" "16V"
			(at 0 0 270)
			(unlocked yes)
			(layer "F.Fab")
			(hide yes)
			(effects
				(font
					(size 1 1)
					(thickness 0.15)
				)
			)
		)
		(property "Dielectric" "X7R"
			(at 0 0 270)
			(unlocked yes)
			(layer "F.Fab")
			(hide yes)
			(effects
				(font
					(size 1 1)
					(thickness 0.15)
				)
			)
		)
		(sheetname "/X710-AT2 PCIe/")
		(sheetfile "x710-at2-pcie.kicad_sch")
		(attr smd)
		(fp_rect
			(start -0.925 -0.47)
			(end 0.925 0.47)
			(stroke
				(width 0.05)
				(type default)
			)
			(fill no)
			(layer "F.CrtYd")
		)
		(fp_line
			(start -0.494 0.248)
			(end -0.494 -0.25)
			(stroke
				(width 0.15)
				(type solid)
			)
			(layer "F.Fab")
		)
		(fp_line
			(start 0.504 0.248)
			(end -0.494 0.248)
			(stroke
				(width 0.15)
				(type solid)
			)
			(layer "F.Fab")
		)
		(fp_line
			(start -0.494 -0.25)
			(end 0.504 -0.25)
			(stroke
				(width 0.15)
				(type solid)
			)
			(layer "F.Fab")
		)
		(fp_line
			(start 0.504 -0.25)
			(end 0.504 0.248)
			(stroke
				(width 0.15)
				(type solid)
			)
			(layer "F.Fab")
		)
		(pad "1" smd roundrect
			(at -0.48 0 270)
			(size 0.59 0.64)
			(layers "F.Cu" "F.Mask" "F.Paste")
			(roundrect_rratio 0.25)
			(net 19 "/OCuLink/PCIe_{x4}.TX1+")
			(pintype "passive")
		)
		(pad "2" smd roundrect
			(at 0.48 0 270)
			(size 0.59 0.64)
			(layers "F.Cu" "F.Mask" "F.Paste")
			(roundrect_rratio 0.25)
			(net 35 "/X710-AT2 PCIe/PCIe_{x4}_AC.TX1+")
			(pintype "passive")
		)
	)
	(footprint "antmicro-footprints:R_0402_1005Metric"
		(layer "F.Cu")
		(at 73.85 78.039994 180)
		(descr "Resistor SMD 0402")
		(tags "resistor SMD 0402")
		(property "Reference" "R6"
			(at -1 3.439994 0)
			(layer "F.SilkS")
			(effects
				(font
					(size 0.7 0.7)
					(thickness 0.15)
				)
				(justify right top)
			)
		)
		(property "Value" "R_20k_0402"
			(at -1.011843 1.772046 0)
			(layer "F.Fab")
			(hide yes)
			(effects
				(font
					(size 0.7 0.7)
					(thickness 0.15)
				)
				(justify right top)
			)
		)
		(property "Datasheet" "https://www.bourns.com/docs/product-datasheets/cr.pdf"
			(at 0 0 0)
			(layer "F.Fab")
			(hide yes)
			(effects
				(font
					(size 1.27 1.27)
					(thickness 0.15)
				)
			)
		)
		(property "Description" "SMD Chip Resistor, 20 kohm, ± 1%, 62.5 mW, 0402 [1005 Metric], Thick Film, General Purpose"
			(at 0 0 0)
			(layer "F.Fab")
			(hide yes)
			(effects
				(font
					(size 1.27 1.27)
					(thickness 0.15)
				)
			)
		)
		(property "MPN" "CR0402-FX-2002GLF"
			(at 0 0 180)
			(unlocked yes)
			(layer "F.Fab")
			(hide yes)
			(effects
				(font
					(size 1 1)
					(thickness 0.15)
				)
			)
		)
		(property "Manufacturer" "Bourns"
			(at 0 0 180)
			(unlocked yes)
			(layer "F.Fab")
			(hide yes)
			(effects
				(font
					(size 1 1)
					(thickness 0.15)
				)
			)
		)
		(property "License" "Apache-2.0"
			(at 0 0 180)
			(unlocked yes)
			(layer "F.Fab")
			(hide yes)
			(effects
				(font
					(size 1 1)
					(thickness 0.15)
				)
			)
		)
		(property "Author" "Antmicro"
			(at 0 0 180)
			(unlocked yes)
			(layer "F.Fab")
			(hide yes)
			(effects
				(font
					(size 1 1)
					(thickness 0.15)
				)
			)
		)
		(property "Val" "20k"
			(at 0 0 180)
			(unlocked yes)
			(layer "F.Fab")
			(hide yes)
			(effects
				(font
					(size 1 1)
					(thickness 0.15)
				)
			)
		)
		(property "Tolerance" "1%"
			(at 0 0 180)
			(unlocked yes)
			(layer "F.Fab")
			(hide yes)
			(effects
				(font
					(size 1 1)
					(thickness 0.15)
				)
			)
		)
		(sheetname "/Power/")
		(sheetfile "power.kicad_sch")
		(attr smd)
		(fp_rect
			(start -0.925 -0.47)
			(end 0.925 0.47)
			(stroke
				(width 0.05)
				(type default)
			)
			(fill no)
			(layer "F.CrtYd")
		)
		(fp_rect
			(start -0.5 -0.25)
			(end 0.5 0.25)
			(stroke
				(width 0.15)
				(type solid)
			)
			(fill no)
			(layer "F.Fab")
		)
		(pad "1" smd roundrect
			(at -0.48 0 180)
			(size 0.59 0.64)
			(layers "F.Cu" "F.Mask" "F.Paste")
			(roundrect_rratio 0.25)
			(net 28 "GND")
			(pintype "passive")
		)
		(pad "2" smd roundrect
			(at 0.48 0 180)
			(size 0.59 0.64)
			(layers "F.Cu" "F.Mask" "F.Paste")
			(roundrect_rratio 0.25)
			(net 317 "/Power/3V3_FB")
			(pintype "passive")
		)
	)
	(footprint "antmicro-footprints:C_0402_1005Metric"
		(layer "F.Cu")
		(at 86.8 68.38)
		(descr "Capacitor SMD 0402")
		(tags "capacitor SMD 0402")
		(property "Reference" "C203"
			(at -1.23 1.43 0)
			(layer "F.SilkS")
			(effects
				(font
					(size 0.7 0.7)
					(thickness 0.15)
				)
				(justify left bottom)
			)
		)
		(property "Value" "C_1u_25V_0402"
			(at -1.022927 2.155213 0)
			(layer "F.Fab")
			(hide yes)
			(effects
				(font
					(size 0.7 0.7)
					(thickness 0.15)
				)
				(justify left bottom)
			)
		)
		(property "Datasheet" "https://www.murata.com/products/productdetail?partno=GRM155R61E105KE11%23"
			(at 0 0 0)
			(layer "F.Fab")
			(hide yes)
			(effects
				(font
					(size 1.27 1.27)
					(thickness 0.15)
				)
			)
		)
		(property "Description" "SMD Multilayer Ceramic Capacitor, 1 µF, 25 V, 0402 [1005 Metric], ± 10%, X5R, GRM Series"
			(at 0 0 0)
			(layer "F.Fab")
			(hide yes)
			(effects
				(font
					(size 1.27 1.27)
					(thickness 0.15)
				)
			)
		)
		(property "MPN" "GRM155R61E105KE11J"
			(at 0 0 0)
			(unlocked yes)
			(layer "F.Fab")
			(hide yes)
			(effects
				(font
					(size 1 1)
					(thickness 0.15)
				)
			)
		)
		(property "Manufacturer" "Murata"
			(at 0 0 0)
			(unlocked yes)
			(layer "F.Fab")
			(hide yes)
			(effects
				(font
					(size 1 1)
					(thickness 0.15)
				)
			)
		)
		(property "License" "Apache-2.0"
			(at 0 0 0)
			(unlocked yes)
			(layer "F.Fab")
			(hide yes)
			(effects
				(font
					(size 1 1)
					(thickness 0.15)
				)
			)
		)
		(property "Author" "Antmicro"
			(at 0 0 0)
			(unlocked yes)
			(layer "F.Fab")
			(hide yes)
			(effects
				(font
					(size 1 1)
					(thickness 0.15)
				)
			)
		)
		(property "Val" "1u"
			(at 0 0 0)
			(unlocked yes)
			(layer "F.Fab")
			(hide yes)
			(effects
				(font
					(size 1 1)
					(thickness 0.15)
				)
			)
		)
		(property "Voltage" "25V"
			(at 0 0 0)
			(unlocked yes)
			(layer "F.Fab")
			(hide yes)
			(effects
				(font
					(size 1 1)
					(thickness 0.15)
				)
			)
		)
		(property "Dielectric" "X5R"
			(at 0 0 0)
			(unlocked yes)
			(layer "F.Fab")
			(hide yes)
			(effects
				(font
					(size 1 1)
					(thickness 0.15)
				)
			)
		)
		(sheetname "/Power/Ideal diode 2/")
		(sheetfile "ideal-diode.kicad_sch")
		(attr smd)
		(fp_rect
			(start -0.925 -0.47)
			(end 0.925 0.47)
			(stroke
				(width 0.05)
				(type default)
			)
			(fill no)
			(layer "F.CrtYd")
		)
		(fp_line
			(start -0.494 -0.25)
			(end 0.504 -0.25)
			(stroke
				(width 0.15)
				(type solid)
			)
			(layer "F.Fab")
		)
		(fp_line
			(start -0.494 0.248)
			(end -0.494 -0.25)
			(stroke
				(width 0.15)
				(type solid)
			)
			(layer "F.Fab")
		)
		(fp_line
			(start 0.504 -0.25)
			(end 0.504 0.248)
			(stroke
				(width 0.15)
				(type solid)
			)
			(layer "F.Fab")
		)
		(fp_line
			(start 0.504 0.248)
			(end -0.494 0.248)
			(stroke
				(width 0.15)
				(type solid)
			)
			(layer "F.Fab")
		)
		(pad "1" smd roundrect
			(at -0.48 0)
			(size 0.59 0.64)
			(layers "F.Cu" "F.Mask" "F.Paste")
			(roundrect_rratio 0.25)
			(net 28 "GND")
			(pintype "passive")
		)
		(pad "2" smd roundrect
			(at 0.48 0)
			(size 0.59 0.64)
			(layers "F.Cu" "F.Mask" "F.Paste")
			(roundrect_rratio 0.25)
			(net 314 "VCC")
			(pintype "passive")
		)
	)
)
